# T6G (Grand Teton) — schematic netlist excerpt (pin names and nets, part order shuffled) for the footprints in the layout excerpt that follows; sources: Cadence DE-HDL packaged netlist, KiCad conversion of 04192023_DAF0TMB3IC0_F0TG_MB_C_brd_V02_OCP.brd

C2481  Q_CAP  22UF 4V 20% X6S  pkg C0402  page 74 : A = PVDD11_S3_P1 ; B = GND
PC460_2  Q_CAP  22UF 4V 20% X6S  pkg C0805  page 222 : A = PVDDIO_P1 ; B = GND

(kicad_pcb
	(version 20260206)
	(generator "pcbnew")
	(generator_version "10.0")
	(general
		(thickness 1.6)
		(legacy_teardrops no)
	)
	(paper "A4")
	(title_block
		(title "04192023_DAF0TMB3IC0_F0TG_MB_C_brd_V02_OCP.brd")
		(comment 1 "Grand Teton / footprints 7807-7808 of 8354")
	)
	(layers
		(0 "F.Cu" signal "TOP")
		(4 "In1.Cu" signal "GND")
		(6 "In2.Cu" signal "IN1")
		(8 "In3.Cu" signal "GND1")
		(10 "In4.Cu" signal "IN2")
		(12 "In5.Cu" signal "GND2")
		(14 "In6.Cu" signal "IN3")
		(16 "In7.Cu" signal "GND3")
		(18 "In8.Cu" signal "VCC")
		(20 "In9.Cu" signal "VCC1")
		(22 "In10.Cu" signal "GND4")
		(24 "In11.Cu" signal "IN4")
		(26 "In12.Cu" signal "GND5")
		(28 "In13.Cu" signal "IN5")
		(30 "In14.Cu" signal "GND6")
		(32 "In15.Cu" signal "IN6")
		(34 "In16.Cu" signal "GND7")
		(2 "B.Cu" signal "BOTTOM")
		(9 "F.Adhes" user "F.Adhesive")
		(11 "B.Adhes" user "B.Adhesive")
		(13 "F.Paste" user "Package Geometry/Pastemask Top")
		(15 "B.Paste" user "Package Geometry/Pastemask Bottom")
		(5 "F.SilkS" user "Ref Des/Silkscreen Top")
		(7 "B.SilkS" user "Ref Des/Silkscreen Bottom")
		(1 "F.Mask" user "Board Geometry/Soldermask Top")
		(3 "B.Mask" user "Board Geometry/Soldermask Bottom")
		(17 "Dwgs.User" user "User.Drawings")
		(19 "Cmts.User" user "User.Comments")
		(21 "Eco1.User" user "User.Eco1")
		(23 "Eco2.User" user "User.Eco2")
		(25 "Edge.Cuts" user "Board Geometry/Outline")
		(27 "Margin" user)
		(31 "F.CrtYd" user "Package Geometry/Place Bound Top")
		(29 "B.CrtYd" user "Package Geometry/Place Bound Bottom")
		(35 "F.Fab" user "Ref Des/Assembly Top")
		(33 "B.Fab" user "Ref Des/Assembly Bottom")
	)
	(footprint ""
		(layer "B.Cu")
		(at 119.674386 -266.005564)
		(property "Reference" "C2481"
			(at 0 0 0)
			(layer "B.SilkS")
			(hide yes)
			(effects
				(font
					(size 1.27 1.27)
				)
				(justify mirror)
			)
		)
		(property "Value" ""
			(at 0 0 0)
			(layer "B.Fab")
			(effects
				(font
					(size 1.27 1.27)
				)
				(justify mirror)
			)
		)
		(duplicate_pad_numbers_are_jumpers no)
		(fp_line
			(start -0.7874 -0.4064)
			(end -0.7874 0.4064)
			(stroke
				(width 0.1524)
				(type default)
			)
			(layer "B.SilkS")
		)
		(fp_line
			(start -0.7874 0.4064)
			(end 0.7874 0.4064)
			(stroke
				(width 0.1524)
				(type default)
			)
			(layer "B.SilkS")
		)
		(fp_line
			(start 0.7874 -0.4064)
			(end -0.7874 -0.4064)
			(stroke
				(width 0.1524)
				(type default)
			)
			(layer "B.SilkS")
		)
		(fp_line
			(start 0.7874 0.4064)
			(end 0.7874 -0.4064)
			(stroke
				(width 0.1524)
				(type default)
			)
			(layer "B.SilkS")
		)
		(fp_line
			(start -0.67945 -0.3048)
			(end -0.67945 0.3048)
			(stroke
				(width 0.1)
				(type default)
			)
			(layer "B.Fab")
		)
		(fp_line
			(start -0.67945 0.3048)
			(end -0.120396 0.3048)
			(stroke
				(width 0.1)
				(type default)
			)
			(layer "B.Fab")
		)
		(fp_line
			(start -0.12065 -0.3048)
			(end -0.67945 -0.3048)
			(stroke
				(width 0.1)
				(type default)
			)
			(layer "B.Fab")
		)
		(fp_line
			(start -0.12065 -0.2794)
			(end -0.12065 -0.3048)
			(stroke
				(width 0.1)
				(type default)
			)
			(layer "B.Fab")
		)
		(fp_line
			(start -0.120396 0.2794)
			(end 0.12065 0.2794)
			(stroke
				(width 0.1)
				(type default)
			)
			(layer "B.Fab")
		)
		(fp_line
			(start -0.120396 0.3048)
			(end -0.120396 0.2794)
			(stroke
				(width 0.1)
				(type default)
			)
			(layer "B.Fab")
		)
		(fp_line
			(start 0.12065 -0.305054)
			(end 0.12065 -0.2794)
			(stroke
				(width 0.1)
				(type default)
			)
			(layer "B.Fab")
		)
		(fp_line
			(start 0.12065 -0.2794)
			(end -0.12065 -0.2794)
			(stroke
				(width 0.1)
				(type default)
			)
			(layer "B.Fab")
		)
		(fp_line
			(start 0.12065 0.2794)
			(end 0.12065 0.3048)
			(stroke
				(width 0.1)
				(type default)
			)
			(layer "B.Fab")
		)
		(fp_line
			(start 0.12065 0.3048)
			(end 0.67945 0.3048)
			(stroke
				(width 0.1)
				(type default)
			)
			(layer "B.Fab")
		)
		(fp_line
			(start 0.67945 -0.305054)
			(end 0.12065 -0.305054)
			(stroke
				(width 0.1)
				(type default)
			)
			(layer "B.Fab")
		)
		(fp_line
			(start 0.67945 0.3048)
			(end 0.67945 -0.305054)
			(stroke
				(width 0.1)
				(type default)
			)
			(layer "B.Fab")
		)
		(pad "1" smd circle
			(at 0.40005 0 180)
			(size 0 0)
			(layers "B.Cu" "B.Mask" "B.Paste")
			(net "PVDD11_S3_P1")
		)
		(pad "2" smd circle
			(at -0.40005 0 180)
			(size 0 0)
			(layers "B.Cu" "B.Mask" "B.Paste")
			(net "GND")
		)
	)
	(footprint ""
		(layer "B.Cu")
		(at 45.332396 -337.989672 -90)
		(property "Reference" "PC460_2"
			(at 0 0 90)
			(layer "B.SilkS")
			(hide yes)
			(effects
				(font
					(size 1.27 1.27)
				)
				(justify mirror)
			)
		)
		(property "Value" ""
			(at 0 0 90)
			(layer "B.Fab")
			(effects
				(font
					(size 1.27 1.27)
				)
				(justify mirror)
			)
		)
		(duplicate_pad_numbers_are_jumpers no)
		(fp_line
			(start -1.524 0.762)
			(end 1.524 0.762)
			(stroke
				(width 0.1524)
				(type default)
			)
			(layer "B.SilkS")
		)
		(fp_line
			(start 1.524 0.762)
			(end 1.524 -0.762)
			(stroke
				(width 0.1524)
				(type default)
			)
			(layer "B.SilkS")
		)
		(fp_line
			(start -1.524 -0.762)
			(end -1.524 0.762)
			(stroke
				(width 0.1524)
				(type default)
			)
			(layer "B.SilkS")
		)
		(fp_line
			(start 1.524 -0.762)
			(end -1.524 -0.762)
			(stroke
				(width 0.1524)
				(type default)
			)
			(layer "B.SilkS")
		)
		(fp_line
			(start -1.1049 0.724916)
			(end -1.1049 -0.724916)
			(stroke
				(width 0.1)
				(type default)
			)
			(layer "B.Fab")
		)
		(fp_line
			(start 1.1049 0.724916)
			(end -1.1049 0.724916)
			(stroke
				(width 0.1)
				(type default)
			)
			(layer "B.Fab")
		)
		(fp_line
			(start -1.1049 -0.724916)
			(end 1.1049 -0.724916)
			(stroke
				(width 0.1)
				(type default)
			)
			(layer "B.Fab")
		)
		(fp_line
			(start 1.1049 -0.724916)
			(end 1.1049 0.724916)
			(stroke
				(width 0.1)
				(type default)
			)
			(layer "B.Fab")
		)
		(pad "1" smd rect
			(at 0.889 0 270)
			(size 1.016 1.27)
			(layers "B.Cu" "B.Mask" "B.Paste")
			(net "PVDDIO_P1")
		)
		(pad "2" smd rect
			(at -0.889 0 270)
			(size 1.016 1.27)
			(layers "B.Cu" "B.Mask" "B.Paste")
			(net "GND")
		)
	)
)
